(kicad_pcb
	(version 20260206)
	(generator "pcbnew")
	(generator_version "10.0")
	(general
		(thickness 1.6)
		(legacy_teardrops no)
	)
	(paper "A4")
	(title_block
		(title "timecard-production-celestica-r4006 — R4006-B0001-02_R01.brd")
		(comment 1 "Time Appliance Project (Time Card) / footprints 930-934 of 1113")
	)
	(layers
		(0 "F.Cu" signal "TOP")
		(4 "In1.Cu" signal "L02_GND1")
		(6 "In2.Cu" signal "L03_SIG1")
		(8 "In3.Cu" signal "L04_GND2")
		(10 "In4.Cu" signal "L05_VCC1")
		(12 "In5.Cu" signal "L06_VCC2")
		(14 "In6.Cu" signal "L07_GND3")
		(16 "In7.Cu" signal "L08_SIG2")
		(18 "In8.Cu" signal "L09_GND4")
		(2 "B.Cu" signal "BOTTOM")
		(9 "F.Adhes" user "F.Adhesive")
		(11 "B.Adhes" user "B.Adhesive")
		(13 "F.Paste" user "Package Geometry/Pastemask Top")
		(15 "B.Paste" user "Package Geometry/Pastemask Bottom")
		(5 "F.SilkS" user "Ref Des/Silkscreen Top")
		(7 "B.SilkS" user "Ref Des/Silkscreen Bottom")
		(1 "F.Mask" user "Board Geometry/Soldermask Top")
		(3 "B.Mask" user "Board Geometry/Soldermask Bottom")
		(17 "Dwgs.User" user "User.Drawings")
		(19 "Cmts.User" user "User.Comments")
		(21 "Eco1.User" user "User.Eco1")
		(23 "Eco2.User" user "User.Eco2")
		(25 "Edge.Cuts" user "Board Geometry/Outline")
		(27 "Margin" user)
		(31 "F.CrtYd" user "Package Geometry/Place Bound Top")
		(29 "B.CrtYd" user "Package Geometry/Place Bound Bottom")
		(35 "F.Fab" user "Ref Des/Assembly Top")
		(33 "B.Fab" user "Ref Des/Assembly Bottom")
	)
	(footprint ""
		(layer "B.Cu")
		(at 105.918 -87.63 -90)
		(property "Reference" "C102"
			(at 0.127 -1.23063 270)
			(unlocked yes)
			(layer "B.SilkS")
			(effects
				(font
					(size 0.7874 0.5842)
					(thickness 0.1524)
				)
				(justify mirror)
			)
		)
		(property "Value" "VAL*"
			(at -0.0762 2.067306 270)
			(unlocked yes)
			(layer "B.Fab")
			(hide yes)
			(effects
				(font
					(size 0.7874 0.5842)
					(thickness 0.1524)
				)
				(justify mirror)
			)
		)
		(property "Tolerance" "TOL*"
			(at -0.0762 3.032506 270)
			(unlocked yes)
			(layer "Cmts.User")
			(hide yes)
			(effects
				(font
					(size 0.7874 0.5842)
					(thickness 0.1524)
				)
				(justify mirror)
			)
		)
		(property "User Part Number" "PARTNUM*"
			(at -0.1016 4.023106 270)
			(unlocked yes)
			(layer "Cmts.User")
			(hide yes)
			(effects
				(font
					(size 0.7874 0.5842)
					(thickness 0.1524)
				)
				(justify mirror)
			)
		)
		(property "Device Type" "CAPACITOR-G105-0B104-EK,0.1UF,A"
			(at -0.0508 1.127506 270)
			(unlocked yes)
			(layer "B.Fab")
			(hide yes)
			(effects
				(font
					(size 0.7874 0.5842)
					(thickness 0.1524)
				)
				(justify mirror)
			)
		)
		(duplicate_pad_numbers_are_jumpers no)
		(fp_line
			(start -1.143 0.5588)
			(end -1.143 -0.5588)
			(stroke
				(width 0.1)
				(type default)
			)
			(layer "B.SilkS")
		)
		(fp_line
			(start 1.143 0.5588)
			(end -1.143 0.5588)
			(stroke
				(width 0.1)
				(type default)
			)
			(layer "B.SilkS")
		)
		(fp_line
			(start -1.143 -0.5588)
			(end 1.143 -0.5588)
			(stroke
				(width 0.1)
				(type default)
			)
			(layer "B.SilkS")
		)
		(fp_line
			(start 1.143 -0.5588)
			(end 1.143 0.5588)
			(stroke
				(width 0.1)
				(type default)
			)
			(layer "B.SilkS")
		)
		(fp_poly
			(pts
				(xy 1.143 0.5588) (xy -1.143 0.5588) (xy -1.143 -0.5588) (xy 1.143 -0.5588)
			)
			(stroke
				(width 0)
				(type default)
			)
			(fill no)
			(layer "B.CrtYd")
		)
		(fp_line
			(start -0.508 0.3048)
			(end -0.508 -0.3048)
			(stroke
				(width 0.1)
				(type default)
			)
			(layer "B.Fab")
		)
		(fp_line
			(start 0.508 0.3048)
			(end -0.508 0.3048)
			(stroke
				(width 0.1)
				(type default)
			)
			(layer "B.Fab")
		)
		(fp_line
			(start -0.508 -0.3048)
			(end 0.508 -0.3048)
			(stroke
				(width 0.1)
				(type default)
			)
			(layer "B.Fab")
		)
		(fp_line
			(start 0.508 -0.3048)
			(end 0.508 0.3048)
			(stroke
				(width 0.1)
				(type default)
			)
			(layer "B.Fab")
		)
		(pad "1" smd rect
			(at 0.5334 0 90)
			(size 0.7112 0.6096)
			(layers "B.Cu" "B.Mask" "B.Paste")
			(net "XP3R3V_FPGA")
		)
		(pad "2" smd rect
			(at -0.5334 0 90)
			(size 0.7112 0.6096)
			(layers "B.Cu" "B.Mask" "B.Paste")
			(net "SG")
		)
		(zone
			(layer "B.Cu")
			(hatch none 0.5)
			(connect_pads
				(clearance 0)
			)
			(min_thickness 0.25)
			(keepout
				(tracks allowed)
				(vias not_allowed)
				(pads allowed)
				(copperpour not_allowed)
				(footprints allowed)
			)
			(placement
				(enabled no)
				(sheetname "")
			)
			(fill
				(thermal_gap 0.5)
				(thermal_bridge_width 0.5)
				(island_removal_mode 0)
			)
			(polygon
				(pts
					(xy 105.6132 -87.5538) (xy 106.2228 -87.5538) (xy 106.2228 -87.7062) (xy 105.6132 -87.7062)
				)
			)
		)
		(zone
			(layer "B.Cu")
			(hatch none 0.5)
			(connect_pads
				(clearance 0)
			)
			(min_thickness 0.25)
			(keepout
				(tracks not_allowed)
				(vias allowed)
				(pads allowed)
				(copperpour not_allowed)
				(footprints allowed)
			)
			(placement
				(enabled no)
				(sheetname "")
			)
			(fill
				(thermal_gap 0.5)
				(thermal_bridge_width 0.5)
				(island_removal_mode 0)
			)
			(polygon
				(pts
					(xy 105.6132 -87.5538) (xy 106.2228 -87.5538) (xy 106.2228 -87.7062) (xy 105.6132 -87.7062)
				)
			)
		)
	)
	(footprint ""
		(layer "B.Cu")
		(at 13.462 -52.578 90)
		(property "Reference" "R495"
			(at 0 1.10363 270)
			(unlocked yes)
			(layer "B.SilkS")
			(effects
				(font
					(size 0.7874 0.5842)
					(thickness 0.1524)
				)
				(justify mirror)
			)
		)
		(property "Value" "VAL*"
			(at -0.02032 2.13233 90)
			(unlocked yes)
			(layer "B.Fab")
			(hide yes)
			(effects
				(font
					(size 0.7874 0.5842)
					(thickness 0.1524)
				)
				(justify mirror)
			)
		)
		(property "Tolerance" "TOL*"
			(at -0.044704 3.05435 90)
			(unlocked yes)
			(layer "Cmts.User")
			(hide yes)
			(effects
				(font
					(size 0.7874 0.5842)
					(thickness 0.1524)
				)
				(justify mirror)
			)
		)
		(property "User Part Number" "PARTNUM*"
			(at -0.02032 4.024884 90)
			(unlocked yes)
			(layer "Cmts.User")
			(hide yes)
			(effects
				(font
					(size 0.7874 0.5842)
					(thickness 0.1524)
				)
				(justify mirror)
			)
		)
		(property "Device Type" "RESISTOR-G155-100R0-J0,0OHM,-"
			(at -0.008382 1.210564 90)
			(unlocked yes)
			(layer "B.Fab")
			(hide yes)
			(effects
				(font
					(size 0.7874 0.5842)
					(thickness 0.1524)
				)
				(justify mirror)
			)
		)
		(duplicate_pad_numbers_are_jumpers no)
		(fp_line
			(start 1.143 -0.5588)
			(end 1.143 0.5588)
			(stroke
				(width 0.1)
				(type default)
			)
			(layer "B.SilkS")
		)
		(fp_line
			(start -1.143 -0.5588)
			(end 1.143 -0.5588)
			(stroke
				(width 0.1)
				(type default)
			)
			(layer "B.SilkS")
		)
		(fp_line
			(start 1.143 0.5588)
			(end -1.143 0.5588)
			(stroke
				(width 0.1)
				(type default)
			)
			(layer "B.SilkS")
		)
		(fp_line
			(start -1.143 0.5588)
			(end -1.143 -0.5588)
			(stroke
				(width 0.1)
				(type default)
			)
			(layer "B.SilkS")
		)
		(fp_poly
			(pts
				(xy 1.143 0.5588) (xy -1.143 0.5588) (xy -1.143 -0.5588) (xy 1.143 -0.5588)
			)
			(stroke
				(width 0)
				(type default)
			)
			(fill no)
			(layer "B.CrtYd")
		)
		(fp_line
			(start 0.508 -0.3048)
			(end 0.508 0.3048)
			(stroke
				(width 0.1)
				(type default)
			)
			(layer "B.Fab")
		)
		(fp_line
			(start -0.508 -0.3048)
			(end 0.508 -0.3048)
			(stroke
				(width 0.1)
				(type default)
			)
			(layer "B.Fab")
		)
		(fp_line
			(start 0.508 0.3048)
			(end -0.508 0.3048)
			(stroke
				(width 0.1)
				(type default)
			)
			(layer "B.Fab")
		)
		(fp_line
			(start -0.508 0.3048)
			(end -0.508 -0.3048)
			(stroke
				(width 0.1)
				(type default)
			)
			(layer "B.Fab")
		)
		(pad "1" smd rect
			(at 0.5334 0 270)
			(size 0.7112 0.6096)
			(layers "B.Cu" "B.Mask" "B.Paste")
			(net "UNNAMED_12_CAPACITOR_I332_2")
		)
		(pad "2" smd rect
			(at -0.5334 0 270)
			(size 0.7112 0.6096)
			(layers "B.Cu" "B.Mask" "B.Paste")
			(net "UNNAMED_12_74HCT2G125DPTSSOP8_9")
		)
		(zone
			(layer "B.Cu")
			(hatch none 0.5)
			(connect_pads
				(clearance 0)
			)
			(min_thickness 0.25)
			(keepout
				(tracks not_allowed)
				(vias allowed)
				(pads allowed)
				(copperpour not_allowed)
				(footprints allowed)
			)
			(placement
				(enabled no)
				(sheetname "")
			)
			(fill
				(thermal_gap 0.5)
				(thermal_bridge_width 0.5)
				(island_removal_mode 0)
			)
			(polygon
				(pts
					(xy 13.7668 -52.6542) (xy 13.1572 -52.6542) (xy 13.1572 -52.5018) (xy 13.7668 -52.5018)
				)
			)
		)
		(zone
			(layer "B.Cu")
			(hatch none 0.5)
			(connect_pads
				(clearance 0)
			)
			(min_thickness 0.25)
			(keepout
				(tracks allowed)
				(vias not_allowed)
				(pads allowed)
				(copperpour not_allowed)
				(footprints allowed)
			)
			(placement
				(enabled no)
				(sheetname "")
			)
			(fill
				(thermal_gap 0.5)
				(thermal_bridge_width 0.5)
				(island_removal_mode 0)
			)
			(polygon
				(pts
					(xy 13.7668 -52.6542) (xy 13.1572 -52.6542) (xy 13.1572 -52.5018) (xy 13.7668 -52.5018)
				)
			)
		)
	)
	(footprint ""
		(layer "B.Cu")
		(at 21.59 -61.5442 -90)
		(property "Reference" "R281"
			(at 3.1242 -0.84963 270)
			(unlocked yes)
			(layer "B.SilkS")
			(effects
				(font
					(size 0.7874 0.5842)
					(thickness 0.1524)
				)
				(justify mirror)
			)
		)
		(property "Value" "VAL*"
			(at -0.02032 2.13233 270)
			(unlocked yes)
			(layer "B.Fab")
			(hide yes)
			(effects
				(font
					(size 0.7874 0.5842)
					(thickness 0.1524)
				)
				(justify mirror)
			)
		)
		(property "Tolerance" "TOL*"
			(at -0.044704 3.05435 270)
			(unlocked yes)
			(layer "Cmts.User")
			(hide yes)
			(effects
				(font
					(size 0.7874 0.5842)
					(thickness 0.1524)
				)
				(justify mirror)
			)
		)
		(property "User Part Number" "PARTNUM*"
			(at -0.02032 4.024884 270)
			(unlocked yes)
			(layer "Cmts.User")
			(hide yes)
			(effects
				(font
					(size 0.7874 0.5842)
					(thickness 0.1524)
				)
				(justify mirror)
			)
		)
		(property "Device Type" "RESISTOR-G155-14701-01,4.7KOHMA"
			(at -0.008382 1.210564 270)
			(unlocked yes)
			(layer "B.Fab")
			(hide yes)
			(effects
				(font
					(size 0.7874 0.5842)
					(thickness 0.1524)
				)
				(justify mirror)
			)
		)
		(duplicate_pad_numbers_are_jumpers no)
		(fp_line
			(start -1.143 0.5588)
			(end -1.143 -0.5588)
			(stroke
				(width 0.1)
				(type default)
			)
			(layer "B.SilkS")
		)
		(fp_line
			(start 1.143 0.5588)
			(end -1.143 0.5588)
			(stroke
				(width 0.1)
				(type default)
			)
			(layer "B.SilkS")
		)
		(fp_line
			(start -1.143 -0.5588)
			(end 1.143 -0.5588)
			(stroke
				(width 0.1)
				(type default)
			)
			(layer "B.SilkS")
		)
		(fp_line
			(start 1.143 -0.5588)
			(end 1.143 0.5588)
			(stroke
				(width 0.1)
				(type default)
			)
			(layer "B.SilkS")
		)
		(fp_poly
			(pts
				(xy 1.143 0.5588) (xy -1.143 0.5588) (xy -1.143 -0.5588) (xy 1.143 -0.5588)
			)
			(stroke
				(width 0)
				(type default)
			)
			(fill no)
			(layer "B.CrtYd")
		)
		(fp_line
			(start -0.508 0.3048)
			(end -0.508 -0.3048)
			(stroke
				(width 0.1)
				(type default)
			)
			(layer "B.Fab")
		)
		(fp_line
			(start 0.508 0.3048)
			(end -0.508 0.3048)
			(stroke
				(width 0.1)
				(type default)
			)
			(layer "B.Fab")
		)
		(fp_line
			(start -0.508 -0.3048)
			(end 0.508 -0.3048)
			(stroke
				(width 0.1)
				(type default)
			)
			(layer "B.Fab")
		)
		(fp_line
			(start 0.508 -0.3048)
			(end 0.508 0.3048)
			(stroke
				(width 0.1)
				(type default)
			)
			(layer "B.Fab")
		)
		(pad "1" smd rect
			(at 0.5334 0 90)
			(size 0.7112 0.6096)
			(layers "B.Cu" "B.Mask" "B.Paste")
			(net "XP3R3V_FPGA")
		)
		(pad "2" smd rect
			(at -0.5334 0 90)
			(size 0.7112 0.6096)
			(layers "B.Cu" "B.Mask" "B.Paste")
			(net "ICP10100_I2C_SDA")
		)
		(zone
			(layer "B.Cu")
			(hatch none 0.5)
			(connect_pads
				(clearance 0)
			)
			(min_thickness 0.25)
			(keepout
				(tracks not_allowed)
				(vias allowed)
				(pads allowed)
				(copperpour not_allowed)
				(footprints allowed)
			)
			(placement
				(enabled no)
				(sheetname "")
			)
			(fill
				(thermal_gap 0.5)
				(thermal_bridge_width 0.5)
				(island_removal_mode 0)
			)
			(polygon
				(pts
					(xy 21.2852 -61.468) (xy 21.8948 -61.468) (xy 21.8948 -61.6204) (xy 21.2852 -61.6204)
				)
			)
		)
		(zone
			(layer "B.Cu")
			(hatch none 0.5)
			(connect_pads
				(clearance 0)
			)
			(min_thickness 0.25)
			(keepout
				(tracks allowed)
				(vias not_allowed)
				(pads allowed)
				(copperpour not_allowed)
				(footprints allowed)
			)
			(placement
				(enabled no)
				(sheetname "")
			)
			(fill
				(thermal_gap 0.5)
				(thermal_bridge_width 0.5)
				(island_removal_mode 0)
			)
			(polygon
				(pts
					(xy 21.2852 -61.468) (xy 21.8948 -61.468) (xy 21.8948 -61.6204) (xy 21.2852 -61.6204)
				)
			)
		)
	)
	(footprint ""
		(layer "B.Cu")
		(at 119.847106 -54.323234 -90)
		(property "Reference" "R504"
			(at -3.461766 -0.001524 270)
			(unlocked yes)
			(layer "B.SilkS")
			(effects
				(font
					(size 0.7874 0.5842)
					(thickness 0.1524)
				)
				(justify mirror)
			)
		)
		(property "Value" "VAL*"
			(at 0 3.718306 270)
			(unlocked yes)
			(layer "B.Fab")
			(hide yes)
			(effects
				(font
					(size 0.7874 0.5842)
					(thickness 0.127)
				)
				(justify mirror)
			)
		)
		(property "Tolerance" "TOL*"
			(at 0 4.861306 270)
			(unlocked yes)
			(layer "Cmts.User")
			(hide yes)
			(effects
				(font
					(size 0.7874 0.5842)
					(thickness 0.127)
				)
				(justify mirror)
			)
		)
		(property "User Part Number" "PARTNUM*"
			(at 0 2.575306 270)
			(unlocked yes)
			(layer "Cmts.User")
			(hide yes)
			(effects
				(font
					(size 0.7874 0.5842)
					(thickness 0.127)
				)
				(justify mirror)
			)
		)
		(property "Device Type" "RESISTOR-G155-14701-01,4.7KOHMA"
			(at 0 1.432306 270)
			(unlocked yes)
			(layer "B.Fab")
			(hide yes)
			(effects
				(font
					(size 0.7874 0.5842)
					(thickness 0.127)
				)
				(justify mirror)
			)
		)
		(duplicate_pad_numbers_are_jumpers no)
		(fp_line
			(start -0.970026 0.4699)
			(end 0.970026 0.4699)
			(stroke
				(width 0.1)
				(type default)
			)
			(layer "B.SilkS")
		)
		(fp_line
			(start 0.970026 0.4699)
			(end 0.970026 -0.4699)
			(stroke
				(width 0.1)
				(type default)
			)
			(layer "B.SilkS")
		)
		(fp_line
			(start -0.970026 -0.4699)
			(end -0.970026 0.4699)
			(stroke
				(width 0.1)
				(type default)
			)
			(layer "B.SilkS")
		)
		(fp_line
			(start 0.970026 -0.4699)
			(end -0.970026 -0.4699)
			(stroke
				(width 0.1)
				(type default)
			)
			(layer "B.SilkS")
		)
		(fp_poly
			(pts
				(xy 0.970026 0.4699) (xy -0.970026 0.4699) (xy -0.970026 -0.4699) (xy 0.970026 -0.4699)
			)
			(stroke
				(width 0)
				(type default)
			)
			(fill no)
			(layer "B.CrtYd")
		)
		(fp_line
			(start -0.508 0.3048)
			(end 0.508 0.3048)
			(stroke
				(width 0.1)
				(type default)
			)
			(layer "B.Fab")
		)
		(fp_line
			(start 0.508 0.3048)
			(end 0.508 -0.3048)
			(stroke
				(width 0.1)
				(type default)
			)
			(layer "B.Fab")
		)
		(fp_line
			(start -0.508 -0.3048)
			(end -0.508 0.3048)
			(stroke
				(width 0.1)
				(type default)
			)
			(layer "B.Fab")
		)
		(fp_line
			(start 0.508 -0.3048)
			(end -0.508 -0.3048)
			(stroke
				(width 0.1)
				(type default)
			)
			(layer "B.Fab")
		)
		(pad "1" smd circle
			(at 0.500126 0 90)
			(size 0.635 0.635)
			(layers "B.Cu" "B.Mask" "B.Paste")
			(net "ANT1_IN")
		)
		(pad "2" smd circle
			(at -0.500126 0 90)
			(size 0.635 0.635)
			(layers "B.Cu" "B.Mask" "B.Paste")
			(net "SG")
		)
	)
	(footprint ""
		(layer "B.Cu")
		(at 113.846864 -49.32299 -90)
		(property "Reference" "C126"
			(at -1.85801 -0.929386 270)
			(unlocked yes)
			(layer "B.SilkS")
			(effects
				(font
					(size 0.635 0.4064)
					(thickness 0.1524)
				)
				(justify mirror)
			)
		)
		(property "Value" "VAL*"
			(at 0 3.718306 270)
			(unlocked yes)
			(layer "B.Fab")
			(hide yes)
			(effects
				(font
					(size 0.7874 0.5842)
					(thickness 0.127)
				)
				(justify mirror)
			)
		)
		(property "Tolerance" "TOL*"
			(at 0 4.861306 270)
			(unlocked yes)
			(layer "Cmts.User")
			(hide yes)
			(effects
				(font
					(size 0.7874 0.5842)
					(thickness 0.127)
				)
				(justify mirror)
			)
		)
		(property "User Part Number" "PARTNUM*"
			(at 0 2.575306 270)
			(unlocked yes)
			(layer "Cmts.User")
			(hide yes)
			(effects
				(font
					(size 0.7874 0.5842)
					(thickness 0.127)
				)
				(justify mirror)
			)
		)
		(property "Device Type" "CAPACITOR-G105-0B104-CK,0.1UF,A"
			(at 0 1.432306 270)
			(unlocked yes)
			(layer "B.Fab")
			(hide yes)
			(effects
				(font
					(size 0.7874 0.5842)
					(thickness 0.127)
				)
				(justify mirror)
			)
		)
		(duplicate_pad_numbers_are_jumpers no)
		(fp_line
			(start -0.970026 0.4699)
			(end 0.970026 0.4699)
			(stroke
				(width 0.1)
				(type default)
			)
			(layer "B.SilkS")
		)
		(fp_line
			(start 0.970026 0.4699)
			(end 0.970026 -0.4699)
			(stroke
				(width 0.1)
				(type default)
			)
			(layer "B.SilkS")
		)
		(fp_line
			(start -0.970026 -0.4699)
			(end -0.970026 0.4699)
			(stroke
				(width 0.1)
				(type default)
			)
			(layer "B.SilkS")
		)
		(fp_line
			(start 0.970026 -0.4699)
			(end -0.970026 -0.4699)
			(stroke
				(width 0.1)
				(type default)
			)
			(layer "B.SilkS")
		)
		(fp_poly
			(pts
				(xy 0.970026 0.4699) (xy -0.970026 0.4699) (xy -0.970026 -0.4699) (xy 0.970026 -0.4699)
			)
			(stroke
				(width 0)
				(type default)
			)
			(fill no)
			(layer "B.CrtYd")
		)
		(fp_line
			(start -0.508 0.3048)
			(end 0.508 0.3048)
			(stroke
				(width 0.1)
				(type default)
			)
			(layer "B.Fab")
		)
		(fp_line
			(start 0.508 0.3048)
			(end 0.508 -0.3048)
			(stroke
				(width 0.1)
				(type default)
			)
			(layer "B.Fab")
		)
		(fp_line
			(start -0.508 -0.3048)
			(end -0.508 0.3048)
			(stroke
				(width 0.1)
				(type default)
			)
			(layer "B.Fab")
		)
		(fp_line
			(start 0.508 -0.3048)
			(end -0.508 -0.3048)
			(stroke
				(width 0.1)
				(type default)
			)
			(layer "B.Fab")
		)
		(pad "1" smd circle
			(at 0.500126 0 90)
			(size 0.635 0.635)
			(layers "B.Cu" "B.Mask" "B.Paste")
			(net "XP3R3V_FPGA")
		)
		(pad "2" smd circle
			(at -0.500126 0 90)
			(size 0.635 0.635)
			(layers "B.Cu" "B.Mask" "B.Paste")
			(net "SG")
		)
	)
)
